# S9S_MB_2U (Grand Teton) — schematic netlist excerpt (pin names and nets, part order shuffled) for the footprints in the layout excerpt that follows; sources: Cadence DE-HDL packaged netlist, KiCad conversion of 03242023_DA0F0TMBIJ0_F0T_Motherboard_J_brd_V01_OCP.brd

C742  Q_CAP_DIFFBUS  DIFF BUS_0.22UF 6.3V 20% X6S  pkg C0201  page 176 : \1\ = P5E_CPU1_PE2_TX_C_DN<15> ; \2\ = P5E_CPU1_PE2_TX_DN<15>
R607  Q_RES  1K 1% EMPTY  pkg 0402LF  page 199 : A = P3V3_AUX ; B = FM_ESPI_FLASH_MODE
R4173  Q_RES  100K 1% EMPTY  pkg 0402LF  page 151 : A = P3V3_AUX ; B = UART_BMC_BIC_R_BUF_RX

(kicad_pcb
	(version 20260206)
	(generator "pcbnew")
	(generator_version "10.0")
	(general
		(thickness 1.6)
		(legacy_teardrops no)
	)
	(paper "A4")
	(title_block
		(title "03242023_DA0F0TMBIJ0_F0T_Motherboard_J_brd_V01_OCP.brd")
		(comment 1 "Grand Teton / footprints 3602-3604 of 6105")
	)
	(layers
		(0 "F.Cu" signal "TOP")
		(4 "In1.Cu" signal "GND")
		(6 "In2.Cu" signal "IN1")
		(8 "In3.Cu" signal "GND1")
		(10 "In4.Cu" signal "IN2")
		(12 "In5.Cu" signal "GND2")
		(14 "In6.Cu" signal "IN3")
		(16 "In7.Cu" signal "GND3")
		(18 "In8.Cu" signal "VCC")
		(20 "In9.Cu" signal "VCC1")
		(22 "In10.Cu" signal "GND4")
		(24 "In11.Cu" signal "IN4")
		(26 "In12.Cu" signal "GND5")
		(28 "In13.Cu" signal "IN5")
		(30 "In14.Cu" signal "GND6")
		(32 "In15.Cu" signal "IN6")
		(34 "In16.Cu" signal "GND7")
		(2 "B.Cu" signal "BOTTOM")
		(9 "F.Adhes" user "F.Adhesive")
		(11 "B.Adhes" user "B.Adhesive")
		(13 "F.Paste" user "Package Geometry/Pastemask Top")
		(15 "B.Paste" user "Package Geometry/Pastemask Bottom")
		(5 "F.SilkS" user "Ref Des/Silkscreen Top")
		(7 "B.SilkS" user "Ref Des/Silkscreen Bottom")
		(1 "F.Mask" user "Board Geometry/Soldermask Top")
		(3 "B.Mask" user "Board Geometry/Soldermask Bottom")
		(17 "Dwgs.User" user "User.Drawings")
		(19 "Cmts.User" user "User.Comments")
		(21 "Eco1.User" user "User.Eco1")
		(23 "Eco2.User" user "User.Eco2")
		(25 "Edge.Cuts" user "Board Geometry/Outline")
		(27 "Margin" user)
		(31 "F.CrtYd" user "Package Geometry/Place Bound Top")
		(29 "B.CrtYd" user "Package Geometry/Place Bound Bottom")
		(35 "F.Fab" user "Ref Des/Assembly Top")
		(33 "B.Fab" user "Ref Des/Assembly Bottom")
	)
	(footprint ""
		(layer "F.Cu")
		(at 309.522622 -44.948348 180)
		(property "Reference" "R607"
			(at 0 0 180)
			(layer "F.SilkS")
			(hide yes)
			(effects
				(font
					(size 1.27 1.27)
				)
			)
		)
		(property "Value" ""
			(at 0 0 180)
			(layer "F.Fab")
			(effects
				(font
					(size 1.27 1.27)
				)
			)
		)
		(duplicate_pad_numbers_are_jumpers no)
		(fp_line
			(start 0.7874 0.4064)
			(end -0.7874 0.4064)
			(stroke
				(width 0.1524)
				(type default)
			)
			(layer "F.SilkS")
		)
		(fp_line
			(start 0.7874 -0.4064)
			(end 0.7874 0.4064)
			(stroke
				(width 0.1524)
				(type default)
			)
			(layer "F.SilkS")
		)
		(fp_line
			(start -0.7874 0.4064)
			(end -0.7874 -0.4064)
			(stroke
				(width 0.1524)
				(type default)
			)
			(layer "F.SilkS")
		)
		(fp_line
			(start -0.7874 -0.4064)
			(end 0.7874 -0.4064)
			(stroke
				(width 0.1524)
				(type default)
			)
			(layer "F.SilkS")
		)
		(fp_line
			(start 0.67945 0.3048)
			(end 0.120396 0.3048)
			(stroke
				(width 0.1)
				(type default)
			)
			(layer "F.Fab")
		)
		(fp_line
			(start 0.67945 -0.3048)
			(end 0.67945 0.3048)
			(stroke
				(width 0.1)
				(type default)
			)
			(layer "F.Fab")
		)
		(fp_line
			(start 0.12065 -0.2794)
			(end 0.12065 -0.3048)
			(stroke
				(width 0.1)
				(type default)
			)
			(layer "F.Fab")
		)
		(fp_line
			(start 0.12065 -0.3048)
			(end 0.67945 -0.3048)
			(stroke
				(width 0.1)
				(type default)
			)
			(layer "F.Fab")
		)
		(fp_line
			(start 0.120396 0.3048)
			(end 0.120396 0.2794)
			(stroke
				(width 0.1)
				(type default)
			)
			(layer "F.Fab")
		)
		(fp_line
			(start 0.120396 0.2794)
			(end -0.12065 0.2794)
			(stroke
				(width 0.1)
				(type default)
			)
			(layer "F.Fab")
		)
		(fp_line
			(start -0.12065 0.3048)
			(end -0.67945 0.3048)
			(stroke
				(width 0.1)
				(type default)
			)
			(layer "F.Fab")
		)
		(fp_line
			(start -0.12065 0.2794)
			(end -0.12065 0.3048)
			(stroke
				(width 0.1)
				(type default)
			)
			(layer "F.Fab")
		)
		(fp_line
			(start -0.12065 -0.2794)
			(end 0.12065 -0.2794)
			(stroke
				(width 0.1)
				(type default)
			)
			(layer "F.Fab")
		)
		(fp_line
			(start -0.12065 -0.305054)
			(end -0.12065 -0.2794)
			(stroke
				(width 0.1)
				(type default)
			)
			(layer "F.Fab")
		)
		(fp_line
			(start -0.67945 0.3048)
			(end -0.67945 -0.305054)
			(stroke
				(width 0.1)
				(type default)
			)
			(layer "F.Fab")
		)
		(fp_line
			(start -0.67945 -0.305054)
			(end -0.12065 -0.305054)
			(stroke
				(width 0.1)
				(type default)
			)
			(layer "F.Fab")
		)
		(pad "1" smd circle
			(at -0.40005 0 180)
			(size 0 0)
			(layers "F.Cu" "F.Mask" "F.Paste")
			(net "P3V3_AUX")
		)
		(pad "2" smd circle
			(at 0.40005 0 180)
			(size 0 0)
			(layers "F.Cu" "F.Mask" "F.Paste")
			(net "FM_ESPI_FLASH_MODE")
		)
	)
	(footprint ""
		(layer "F.Cu")
		(at 368.72164 -403.936708 180)
		(property "Reference" "R4173"
			(at 0 0 180)
			(layer "F.SilkS")
			(hide yes)
			(effects
				(font
					(size 1.27 1.27)
				)
			)
		)
		(property "Value" ""
			(at 0 0 180)
			(layer "F.Fab")
			(effects
				(font
					(size 1.27 1.27)
				)
			)
		)
		(duplicate_pad_numbers_are_jumpers no)
		(fp_line
			(start 0.7874 0.4064)
			(end -0.7874 0.4064)
			(stroke
				(width 0.1524)
				(type default)
			)
			(layer "F.SilkS")
		)
		(fp_line
			(start 0.7874 -0.4064)
			(end 0.7874 0.4064)
			(stroke
				(width 0.1524)
				(type default)
			)
			(layer "F.SilkS")
		)
		(fp_line
			(start -0.7874 0.4064)
			(end -0.7874 -0.4064)
			(stroke
				(width 0.1524)
				(type default)
			)
			(layer "F.SilkS")
		)
		(fp_line
			(start -0.7874 -0.4064)
			(end 0.7874 -0.4064)
			(stroke
				(width 0.1524)
				(type default)
			)
			(layer "F.SilkS")
		)
		(fp_line
			(start 0.67945 0.3048)
			(end 0.120396 0.3048)
			(stroke
				(width 0.1)
				(type default)
			)
			(layer "F.Fab")
		)
		(fp_line
			(start 0.67945 -0.3048)
			(end 0.67945 0.3048)
			(stroke
				(width 0.1)
				(type default)
			)
			(layer "F.Fab")
		)
		(fp_line
			(start 0.12065 -0.2794)
			(end 0.12065 -0.3048)
			(stroke
				(width 0.1)
				(type default)
			)
			(layer "F.Fab")
		)
		(fp_line
			(start 0.12065 -0.3048)
			(end 0.67945 -0.3048)
			(stroke
				(width 0.1)
				(type default)
			)
			(layer "F.Fab")
		)
		(fp_line
			(start 0.120396 0.3048)
			(end 0.120396 0.2794)
			(stroke
				(width 0.1)
				(type default)
			)
			(layer "F.Fab")
		)
		(fp_line
			(start 0.120396 0.2794)
			(end -0.12065 0.2794)
			(stroke
				(width 0.1)
				(type default)
			)
			(layer "F.Fab")
		)
		(fp_line
			(start -0.12065 0.3048)
			(end -0.67945 0.3048)
			(stroke
				(width 0.1)
				(type default)
			)
			(layer "F.Fab")
		)
		(fp_line
			(start -0.12065 0.2794)
			(end -0.12065 0.3048)
			(stroke
				(width 0.1)
				(type default)
			)
			(layer "F.Fab")
		)
		(fp_line
			(start -0.12065 -0.2794)
			(end 0.12065 -0.2794)
			(stroke
				(width 0.1)
				(type default)
			)
			(layer "F.Fab")
		)
		(fp_line
			(start -0.12065 -0.305054)
			(end -0.12065 -0.2794)
			(stroke
				(width 0.1)
				(type default)
			)
			(layer "F.Fab")
		)
		(fp_line
			(start -0.67945 0.3048)
			(end -0.67945 -0.305054)
			(stroke
				(width 0.1)
				(type default)
			)
			(layer "F.Fab")
		)
		(fp_line
			(start -0.67945 -0.305054)
			(end -0.12065 -0.305054)
			(stroke
				(width 0.1)
				(type default)
			)
			(layer "F.Fab")
		)
		(pad "1" smd circle
			(at -0.40005 0 180)
			(size 0 0)
			(layers "F.Cu" "F.Mask" "F.Paste")
			(net "P3V3_AUX")
		)
		(pad "2" smd circle
			(at 0.40005 0 180)
			(size 0 0)
			(layers "F.Cu" "F.Mask" "F.Paste")
			(net "UART_BMC_BIC_R_BUF_RX")
		)
	)
	(footprint ""
		(layer "F.Cu")
		(at 121.043954 -402.371052 -90)
		(property "Reference" "C742"
			(at 0 0 270)
			(layer "F.SilkS")
			(hide yes)
			(effects
				(font
					(size 1.27 1.27)
				)
			)
		)
		(property "Value" ""
			(at 0 0 270)
			(layer "F.Fab")
			(effects
				(font
					(size 1.27 1.27)
				)
			)
		)
		(duplicate_pad_numbers_are_jumpers no)
		(fp_line
			(start -0.299974 0.150114)
			(end -0.299974 -0.150114)
			(stroke
				(width 0.1)
				(type default)
			)
			(layer "F.Fab")
		)
		(fp_line
			(start 0.299974 0.150114)
			(end -0.299974 0.150114)
			(stroke
				(width 0.1)
				(type default)
			)
			(layer "F.Fab")
		)
		(fp_line
			(start -0.299974 -0.150114)
			(end 0.299974 -0.150114)
			(stroke
				(width 0.1)
				(type default)
			)
			(layer "F.Fab")
		)
		(fp_line
			(start 0.299974 -0.150114)
			(end 0.299974 0.150114)
			(stroke
				(width 0.1)
				(type default)
			)
			(layer "F.Fab")
		)
		(pad "1" smd rect
			(at -0.2667 0 270)
			(size 0.3048 0.381)
			(layers "F.Cu" "F.Mask" "F.Paste")
			(net "P5E_CPU1_PE2_TX_C_DN<15>")
		)
		(pad "2" smd rect
			(at 0.2667 0 270)
			(size 0.3048 0.381)
			(layers "F.Cu" "F.Mask" "F.Paste")
			(net "P5E_CPU1_PE2_TX_DN<15>")
		)
	)
)
